# BASEBOARD_FAB2 (Tioga Pass) — schematic netlist excerpt (pin names and nets, part order shuffled) for the footprints in the layout excerpt that follows; sources: Cadence DE-HDL packaged netlist, KiCad conversion of Wiwynn_Tioga_Pass_MB.brd

R3M5  RES  100.0K 1% EMPTY  pkg 0402  page 218 : A = P3V3_STBY ; B = VR_PVDDQ_DEF_VREN
R3W5  RES  10.0K 1% CHIP  pkg 0402  page 249 : A = P3V3_STBY ; B = FM_TPM_PRES_RST
C6P17  CAP  10UF 16V 10% X6S  pkg 0805  page 204 : A = VR_FET_SW_P12V_STBY_PVCCIN_CPU0 ; B = GND

(kicad_pcb
	(version 20260206)
	(generator "pcbnew")
	(generator_version "10.0")
	(general
		(thickness 1.6)
		(legacy_teardrops no)
	)
	(paper "A4")
	(title_block
		(title "Wiwynn_Tioga_Pass_MB.brd")
		(comment 1 "Tioga Pass / footprints 2784-2786 of 4770")
	)
	(layers
		(0 "F.Cu" signal "TOP")
		(4 "In1.Cu" signal "L2GND")
		(6 "In2.Cu" signal "L3")
		(8 "In3.Cu" signal "L4GND")
		(10 "In4.Cu" signal "L5")
		(12 "In5.Cu" signal "L6GND")
		(14 "In6.Cu" signal "L7VCC")
		(16 "In7.Cu" signal "L8VCC")
		(18 "In8.Cu" signal "L9GND")
		(20 "In9.Cu" signal "L10")
		(22 "In10.Cu" signal "L11GND")
		(24 "In11.Cu" signal "L12")
		(26 "In12.Cu" signal "L13GND")
		(2 "B.Cu" signal "BOTTOM")
		(9 "F.Adhes" user "F.Adhesive")
		(11 "B.Adhes" user "B.Adhesive")
		(13 "F.Paste" user "Package Geometry/Pastemask Top")
		(15 "B.Paste" user "Package Geometry/Pastemask Bottom")
		(5 "F.SilkS" user "Ref Des/Silkscreen Top")
		(7 "B.SilkS" user "Ref Des/Silkscreen Bottom")
		(1 "F.Mask" user "Board Geometry/Soldermask Top")
		(3 "B.Mask" user "Board Geometry/Soldermask Bottom")
		(17 "Dwgs.User" user "User.Drawings")
		(19 "Cmts.User" user "User.Comments")
		(21 "Eco1.User" user "User.Eco1")
		(23 "Eco2.User" user "User.Eco2")
		(25 "Edge.Cuts" user "Board Geometry/Outline")
		(27 "Margin" user)
		(31 "F.CrtYd" user "Package Geometry/Place Bound Top")
		(29 "B.CrtYd" user "Package Geometry/Place Bound Bottom")
		(35 "F.Fab" user "Ref Des/Assembly Top")
		(33 "B.Fab" user "Ref Des/Assembly Bottom")
	)
	(footprint ""
		(layer "B.Cu")
		(at 197.848728 -76.157582 90)
		(property "Reference" "C6P17"
			(at 0 0 90)
			(layer "B.SilkS")
			(hide yes)
			(effects
				(font
					(size 1.27 1.27)
				)
				(justify mirror)
			)
		)
		(property "Value" ""
			(at 0 0 90)
			(layer "B.Fab")
			(effects
				(font
					(size 1.27 1.27)
				)
				(justify mirror)
			)
		)
		(duplicate_pad_numbers_are_jumpers no)
		(fp_rect
			(start -0.7239 -0.2159)
			(end 0.7239 1.9939)
			(stroke
				(width 0)
				(type default)
			)
			(fill no)
			(layer "B.CrtYd")
		)
		(fp_line
			(start 0.7239 -0.2159)
			(end 0.7239 1.9939)
			(stroke
				(width 0.1)
				(type default)
			)
			(layer "B.Fab")
		)
		(fp_line
			(start -0.7239 -0.2159)
			(end 0.7239 -0.2159)
			(stroke
				(width 0.1)
				(type default)
			)
			(layer "B.Fab")
		)
		(fp_line
			(start 0.7239 1.9939)
			(end -0.7239 1.9939)
			(stroke
				(width 0.1)
				(type default)
			)
			(layer "B.Fab")
		)
		(fp_line
			(start -0.7239 1.9939)
			(end -0.7239 -0.2159)
			(stroke
				(width 0.1)
				(type default)
			)
			(layer "B.Fab")
		)
		(pad "1" smd rect
			(at 0 0 270)
			(size 1.27 1.016)
			(layers "B.Cu" "B.Mask" "B.Paste")
			(net "VR_FET_SW_P12V_STBY_PVCCIN_CPU0")
		)
		(pad "2" smd rect
			(at 0 1.778 270)
			(size 1.27 1.016)
			(layers "B.Cu" "B.Mask" "B.Paste")
			(net "GND")
		)
		(zone
			(layer "B.Cu")
			(hatch none 0.5)
			(connect_pads
				(clearance 0)
			)
			(min_thickness 0.25)
			(keepout
				(tracks not_allowed)
				(vias allowed)
				(pads allowed)
				(copperpour not_allowed)
				(footprints allowed)
			)
			(placement
				(enabled no)
				(sheetname "")
			)
			(fill
				(thermal_gap 0.5)
				(thermal_bridge_width 0.5)
				(island_removal_mode 0)
			)
			(polygon
				(pts
					(xy 198.356728 -75.522582) (xy 199.118728 -75.522582) (xy 199.118728 -76.792582) (xy 198.356728 -76.792582)
				)
			)
		)
	)
	(footprint ""
		(layer "B.Cu")
		(at 439.02884 -21.29282 90)
		(property "Reference" "R3W5"
			(at 0.8382 -0.67818 90)
			(unlocked yes)
			(layer "B.SilkS")
			(effects
				(font
					(size 0.4064 0.254)
					(thickness 0.1524)
				)
				(justify left mirror)
			)
		)
		(property "Value" ""
			(at 0 0 90)
			(layer "B.Fab")
			(effects
				(font
					(size 1.27 1.27)
				)
				(justify mirror)
			)
		)
		(duplicate_pad_numbers_are_jumpers no)
		(fp_poly
			(pts
				(xy 0.2794 -0.1016) (xy -0.2794 -0.1016) (xy -0.2794 0.9906) (xy 0.2794 0.9906)
			)
			(stroke
				(width 0)
				(type default)
			)
			(fill no)
			(layer "B.CrtYd")
		)
		(fp_line
			(start 0.2794 -0.1016)
			(end 0.2794 0.9906)
			(stroke
				(width 0.1)
				(type default)
			)
			(layer "B.Fab")
		)
		(fp_line
			(start -0.2794 -0.1016)
			(end 0.2794 -0.1016)
			(stroke
				(width 0.1)
				(type default)
			)
			(layer "B.Fab")
		)
		(fp_line
			(start 0.2794 0.9906)
			(end -0.2794 0.9906)
			(stroke
				(width 0.1)
				(type default)
			)
			(layer "B.Fab")
		)
		(fp_line
			(start -0.2794 0.9906)
			(end -0.2794 -0.1016)
			(stroke
				(width 0.1)
				(type default)
			)
			(layer "B.Fab")
		)
		(pad "1" smd rect
			(at 0 0 270)
			(size 0.508 0.508)
			(layers "B.Cu" "B.Mask" "B.Paste")
			(net "P3V3_STBY")
		)
		(pad "2" smd rect
			(at 0 0.889 270)
			(size 0.508 0.508)
			(layers "B.Cu" "B.Mask" "B.Paste")
			(net "FM_TPM_PRES_RST")
		)
		(zone
			(layer "B.Cu")
			(hatch none 0.5)
			(connect_pads
				(clearance 0)
			)
			(min_thickness 0.25)
			(keepout
				(tracks allowed)
				(vias not_allowed)
				(pads allowed)
				(copperpour not_allowed)
				(footprints allowed)
			)
			(placement
				(enabled no)
				(sheetname "")
			)
			(fill
				(thermal_gap 0.5)
				(thermal_bridge_width 0.5)
				(island_removal_mode 0)
			)
			(polygon
				(pts
					(xy 439.28284 -21.54682) (xy 439.28284 -21.03882) (xy 439.66384 -21.03882) (xy 439.66384 -21.54682)
				)
			)
		)
		(zone
			(layer "B.Cu")
			(hatch none 0.5)
			(connect_pads
				(clearance 0)
			)
			(min_thickness 0.25)
			(keepout
				(tracks not_allowed)
				(vias allowed)
				(pads allowed)
				(copperpour not_allowed)
				(footprints allowed)
			)
			(placement
				(enabled no)
				(sheetname "")
			)
			(fill
				(thermal_gap 0.5)
				(thermal_bridge_width 0.5)
				(island_removal_mode 0)
			)
			(polygon
				(pts
					(xy 439.66384 -21.54682) (xy 439.66384 -21.03882) (xy 439.28284 -21.03882) (xy 439.28284 -21.54682)
				)
			)
		)
	)
	(footprint ""
		(layer "B.Cu")
		(at 362.1024 -133.0198 180)
		(property "Reference" "R3M5"
			(at 0 0 0)
			(layer "B.SilkS")
			(hide yes)
			(effects
				(font
					(size 1.27 1.27)
				)
				(justify mirror)
			)
		)
		(property "Value" ""
			(at 0 0 0)
			(layer "B.Fab")
			(effects
				(font
					(size 1.27 1.27)
				)
				(justify mirror)
			)
		)
		(duplicate_pad_numbers_are_jumpers no)
		(fp_poly
			(pts
				(xy 0.2794 -0.1016) (xy -0.2794 -0.1016) (xy -0.2794 0.9906) (xy 0.2794 0.9906)
			)
			(stroke
				(width 0)
				(type default)
			)
			(fill no)
			(layer "B.CrtYd")
		)
		(fp_line
			(start 0.2794 0.9906)
			(end -0.2794 0.9906)
			(stroke
				(width 0.1)
				(type default)
			)
			(layer "B.Fab")
		)
		(fp_line
			(start 0.2794 -0.1016)
			(end 0.2794 0.9906)
			(stroke
				(width 0.1)
				(type default)
			)
			(layer "B.Fab")
		)
		(fp_line
			(start -0.2794 0.9906)
			(end -0.2794 -0.1016)
			(stroke
				(width 0.1)
				(type default)
			)
			(layer "B.Fab")
		)
		(fp_line
			(start -0.2794 -0.1016)
			(end 0.2794 -0.1016)
			(stroke
				(width 0.1)
				(type default)
			)
			(layer "B.Fab")
		)
		(pad "1" smd rect
			(at 0 0)
			(size 0.508 0.508)
			(layers "B.Cu" "B.Mask" "B.Paste")
			(net "P3V3_STBY")
		)
		(pad "2" smd rect
			(at 0 0.889)
			(size 0.508 0.508)
			(layers "B.Cu" "B.Mask" "B.Paste")
			(net "VR_PVDDQ_DEF_VREN")
		)
		(zone
			(layer "B.Cu")
			(hatch none 0.5)
			(connect_pads
				(clearance 0)
			)
			(min_thickness 0.25)
			(keepout
				(tracks not_allowed)
				(vias allowed)
				(pads allowed)
				(copperpour not_allowed)
				(footprints allowed)
			)
			(placement
				(enabled no)
				(sheetname "")
			)
			(fill
				(thermal_gap 0.5)
				(thermal_bridge_width 0.5)
				(island_removal_mode 0)
			)
			(polygon
				(pts
					(xy 361.8484 -133.6548) (xy 362.3564 -133.6548) (xy 362.3564 -133.2738) (xy 361.8484 -133.2738)
				)
			)
		)
		(zone
			(layer "B.Cu")
			(hatch none 0.5)
			(connect_pads
				(clearance 0)
			)
			(min_thickness 0.25)
			(keepout
				(tracks allowed)
				(vias not_allowed)
				(pads allowed)
				(copperpour not_allowed)
				(footprints allowed)
			)
			(placement
				(enabled no)
				(sheetname "")
			)
			(fill
				(thermal_gap 0.5)
				(thermal_bridge_width 0.5)
				(island_removal_mode 0)
			)
			(polygon
				(pts
					(xy 361.8484 -133.2738) (xy 362.3564 -133.2738) (xy 362.3564 -133.6548) (xy 361.8484 -133.6548)
				)
			)
		)
	)
)
